(kicad_pcb
	(version 20260206)
	(generator "pcbnew")
	(generator_version "10.0")
	(general
		(thickness 1.6)
		(legacy_teardrops no)
	)
	(paper "A4")
	(title_block
		(title "04192023_DAF0TMB3IC0_F0TG_MB_C_brd_V02_OCP.brd")
		(comment 1 "Grand Teton / footprints 503-509 of 8354")
	)
	(layers
		(0 "F.Cu" signal "TOP")
		(4 "In1.Cu" signal "GND")
		(6 "In2.Cu" signal "IN1")
		(8 "In3.Cu" signal "GND1")
		(10 "In4.Cu" signal "IN2")
		(12 "In5.Cu" signal "GND2")
		(14 "In6.Cu" signal "IN3")
		(16 "In7.Cu" signal "GND3")
		(18 "In8.Cu" signal "VCC")
		(20 "In9.Cu" signal "VCC1")
		(22 "In10.Cu" signal "GND4")
		(24 "In11.Cu" signal "IN4")
		(26 "In12.Cu" signal "GND5")
		(28 "In13.Cu" signal "IN5")
		(30 "In14.Cu" signal "GND6")
		(32 "In15.Cu" signal "IN6")
		(34 "In16.Cu" signal "GND7")
		(2 "B.Cu" signal "BOTTOM")
		(9 "F.Adhes" user "F.Adhesive")
		(11 "B.Adhes" user "B.Adhesive")
		(13 "F.Paste" user "Package Geometry/Pastemask Top")
		(15 "B.Paste" user "Package Geometry/Pastemask Bottom")
		(5 "F.SilkS" user "Ref Des/Silkscreen Top")
		(7 "B.SilkS" user "Ref Des/Silkscreen Bottom")
		(1 "F.Mask" user "Board Geometry/Soldermask Top")
		(3 "B.Mask" user "Board Geometry/Soldermask Bottom")
		(17 "Dwgs.User" user "User.Drawings")
		(19 "Cmts.User" user "User.Comments")
		(21 "Eco1.User" user "User.Eco1")
		(23 "Eco2.User" user "User.Eco2")
		(25 "Edge.Cuts" user "Board Geometry/Outline")
		(27 "Margin" user)
		(31 "F.CrtYd" user "Package Geometry/Place Bound Top")
		(29 "B.CrtYd" user "Package Geometry/Place Bound Bottom")
		(35 "F.Fab" user "Ref Des/Assembly Top")
		(33 "B.Fab" user "Ref Des/Assembly Bottom")
	)
	(footprint ""
		(layer "F.Cu")
		(at 255.45669 -40.498522 -90)
		(property "Reference" "PC2215"
			(at 0 0 270)
			(layer "F.SilkS")
			(hide yes)
			(effects
				(font
					(size 1.27 1.27)
				)
			)
		)
		(property "Value" ""
			(at 0 0 270)
			(layer "F.Fab")
			(effects
				(font
					(size 1.27 1.27)
				)
			)
		)
		(duplicate_pad_numbers_are_jumpers no)
		(fp_line
			(start -0.7874 0.4064)
			(end -0.7874 -0.4064)
			(stroke
				(width 0.1524)
				(type default)
			)
			(layer "F.SilkS")
		)
		(fp_line
			(start 0.7874 0.4064)
			(end -0.7874 0.4064)
			(stroke
				(width 0.1524)
				(type default)
			)
			(layer "F.SilkS")
		)
		(fp_line
			(start -0.7874 -0.4064)
			(end 0.7874 -0.4064)
			(stroke
				(width 0.1524)
				(type default)
			)
			(layer "F.SilkS")
		)
		(fp_line
			(start 0.7874 -0.4064)
			(end 0.7874 0.4064)
			(stroke
				(width 0.1524)
				(type default)
			)
			(layer "F.SilkS")
		)
		(fp_line
			(start -0.67945 0.3048)
			(end -0.67945 -0.305054)
			(stroke
				(width 0.1)
				(type default)
			)
			(layer "F.Fab")
		)
		(fp_line
			(start -0.12065 0.3048)
			(end -0.67945 0.3048)
			(stroke
				(width 0.1)
				(type default)
			)
			(layer "F.Fab")
		)
		(fp_line
			(start 0.120396 0.3048)
			(end 0.120396 0.2794)
			(stroke
				(width 0.1)
				(type default)
			)
			(layer "F.Fab")
		)
		(fp_line
			(start 0.67945 0.3048)
			(end 0.120396 0.3048)
			(stroke
				(width 0.1)
				(type default)
			)
			(layer "F.Fab")
		)
		(fp_line
			(start -0.12065 0.2794)
			(end -0.12065 0.3048)
			(stroke
				(width 0.1)
				(type default)
			)
			(layer "F.Fab")
		)
		(fp_line
			(start 0.120396 0.2794)
			(end -0.12065 0.2794)
			(stroke
				(width 0.1)
				(type default)
			)
			(layer "F.Fab")
		)
		(fp_line
			(start -0.12065 -0.2794)
			(end 0.12065 -0.2794)
			(stroke
				(width 0.1)
				(type default)
			)
			(layer "F.Fab")
		)
		(fp_line
			(start 0.12065 -0.2794)
			(end 0.12065 -0.3048)
			(stroke
				(width 0.1)
				(type default)
			)
			(layer "F.Fab")
		)
		(fp_line
			(start 0.12065 -0.3048)
			(end 0.67945 -0.3048)
			(stroke
				(width 0.1)
				(type default)
			)
			(layer "F.Fab")
		)
		(fp_line
			(start 0.67945 -0.3048)
			(end 0.67945 0.3048)
			(stroke
				(width 0.1)
				(type default)
			)
			(layer "F.Fab")
		)
		(fp_line
			(start -0.67945 -0.305054)
			(end -0.12065 -0.305054)
			(stroke
				(width 0.1)
				(type default)
			)
			(layer "F.Fab")
		)
		(fp_line
			(start -0.12065 -0.305054)
			(end -0.12065 -0.2794)
			(stroke
				(width 0.1)
				(type default)
			)
			(layer "F.Fab")
		)
		(pad "1" smd circle
			(at -0.40005 0 270)
			(size 0 0)
			(layers "F.Cu" "F.Mask" "F.Paste")
			(net "P12V_E1S_GATE_0")
		)
		(pad "2" smd circle
			(at 0.40005 0 270)
			(size 0 0)
			(layers "F.Cu" "F.Mask" "F.Paste")
			(net "GND")
		)
	)
	(footprint ""
		(layer "F.Cu")
		(at 298.967144 -384.32486 180)
		(property "Reference" "C931"
			(at 0 0 180)
			(layer "F.SilkS")
			(hide yes)
			(effects
				(font
					(size 1.27 1.27)
				)
			)
		)
		(property "Value" ""
			(at 0 0 180)
			(layer "F.Fab")
			(effects
				(font
					(size 1.27 1.27)
				)
			)
		)
		(duplicate_pad_numbers_are_jumpers no)
		(fp_line
			(start 0.299974 0.150114)
			(end -0.299974 0.150114)
			(stroke
				(width 0.1)
				(type default)
			)
			(layer "F.Fab")
		)
		(fp_line
			(start 0.299974 -0.150114)
			(end 0.299974 0.150114)
			(stroke
				(width 0.1)
				(type default)
			)
			(layer "F.Fab")
		)
		(fp_line
			(start -0.299974 0.150114)
			(end -0.299974 -0.150114)
			(stroke
				(width 0.1)
				(type default)
			)
			(layer "F.Fab")
		)
		(fp_line
			(start -0.299974 -0.150114)
			(end 0.299974 -0.150114)
			(stroke
				(width 0.1)
				(type default)
			)
			(layer "F.Fab")
		)
		(pad "1" smd rect
			(at -0.2667 0 180)
			(size 0.3048 0.381)
			(layers "F.Cu" "F.Mask" "F.Paste")
			(net "P5E_CPU0_P0_TX_C_DP<1>")
		)
		(pad "2" smd rect
			(at 0.2667 0 180)
			(size 0.3048 0.381)
			(layers "F.Cu" "F.Mask" "F.Paste")
			(net "P5E_CPU0_P0_TX_DP<1>")
		)
	)
	(footprint ""
		(layer "F.Cu")
		(at 216.982548 -133.200902 180)
		(property "Reference" "R6119"
			(at 0 0 180)
			(layer "F.SilkS")
			(hide yes)
			(effects
				(font
					(size 1.27 1.27)
				)
			)
		)
		(property "Value" ""
			(at 0 0 180)
			(layer "F.Fab")
			(effects
				(font
					(size 1.27 1.27)
				)
			)
		)
		(duplicate_pad_numbers_are_jumpers no)
		(fp_line
			(start 0.7874 0.4064)
			(end -0.7874 0.4064)
			(stroke
				(width 0.1524)
				(type default)
			)
			(layer "F.SilkS")
		)
		(fp_line
			(start 0.7874 -0.4064)
			(end 0.7874 0.4064)
			(stroke
				(width 0.1524)
				(type default)
			)
			(layer "F.SilkS")
		)
		(fp_line
			(start -0.7874 0.4064)
			(end -0.7874 -0.4064)
			(stroke
				(width 0.1524)
				(type default)
			)
			(layer "F.SilkS")
		)
		(fp_line
			(start -0.7874 -0.4064)
			(end 0.7874 -0.4064)
			(stroke
				(width 0.1524)
				(type default)
			)
			(layer "F.SilkS")
		)
		(fp_line
			(start 0.67945 0.3048)
			(end 0.120396 0.3048)
			(stroke
				(width 0.1)
				(type default)
			)
			(layer "F.Fab")
		)
		(fp_line
			(start 0.67945 -0.3048)
			(end 0.67945 0.3048)
			(stroke
				(width 0.1)
				(type default)
			)
			(layer "F.Fab")
		)
		(fp_line
			(start 0.12065 -0.2794)
			(end 0.12065 -0.3048)
			(stroke
				(width 0.1)
				(type default)
			)
			(layer "F.Fab")
		)
		(fp_line
			(start 0.12065 -0.3048)
			(end 0.67945 -0.3048)
			(stroke
				(width 0.1)
				(type default)
			)
			(layer "F.Fab")
		)
		(fp_line
			(start 0.120396 0.3048)
			(end 0.120396 0.2794)
			(stroke
				(width 0.1)
				(type default)
			)
			(layer "F.Fab")
		)
		(fp_line
			(start 0.120396 0.2794)
			(end -0.12065 0.2794)
			(stroke
				(width 0.1)
				(type default)
			)
			(layer "F.Fab")
		)
		(fp_line
			(start -0.12065 0.3048)
			(end -0.67945 0.3048)
			(stroke
				(width 0.1)
				(type default)
			)
			(layer "F.Fab")
		)
		(fp_line
			(start -0.12065 0.2794)
			(end -0.12065 0.3048)
			(stroke
				(width 0.1)
				(type default)
			)
			(layer "F.Fab")
		)
		(fp_line
			(start -0.12065 -0.2794)
			(end 0.12065 -0.2794)
			(stroke
				(width 0.1)
				(type default)
			)
			(layer "F.Fab")
		)
		(fp_line
			(start -0.12065 -0.305054)
			(end -0.12065 -0.2794)
			(stroke
				(width 0.1)
				(type default)
			)
			(layer "F.Fab")
		)
		(fp_line
			(start -0.67945 0.3048)
			(end -0.67945 -0.305054)
			(stroke
				(width 0.1)
				(type default)
			)
			(layer "F.Fab")
		)
		(fp_line
			(start -0.67945 -0.305054)
			(end -0.12065 -0.305054)
			(stroke
				(width 0.1)
				(type default)
			)
			(layer "F.Fab")
		)
		(pad "1" smd circle
			(at -0.40005 0 180)
			(size 0 0)
			(layers "F.Cu" "F.Mask" "F.Paste")
			(net "PWRGD_P3V3_AUX")
		)
		(pad "2" smd circle
			(at 0.40005 0 180)
			(size 0 0)
			(layers "F.Cu" "F.Mask" "F.Paste")
			(net "P1V8_AUX_ENABLE")
		)
	)
	(footprint ""
		(layer "F.Cu")
		(at 84.42833 -339.835998 90)
		(property "Reference" "PC374_1"
			(at 0 0 90)
			(layer "F.SilkS")
			(hide yes)
			(effects
				(font
					(size 1.27 1.27)
				)
			)
		)
		(property "Value" ""
			(at 0 0 90)
			(layer "F.Fab")
			(effects
				(font
					(size 1.27 1.27)
				)
			)
		)
		(duplicate_pad_numbers_are_jumpers no)
		(fp_line
			(start 0.7874 -0.4064)
			(end 0.7874 0.4064)
			(stroke
				(width 0.1524)
				(type default)
			)
			(layer "F.SilkS")
		)
		(fp_line
			(start -0.7874 -0.4064)
			(end 0.7874 -0.4064)
			(stroke
				(width 0.1524)
				(type default)
			)
			(layer "F.SilkS")
		)
		(fp_line
			(start 0.7874 0.4064)
			(end -0.7874 0.4064)
			(stroke
				(width 0.1524)
				(type default)
			)
			(layer "F.SilkS")
		)
		(fp_line
			(start -0.7874 0.4064)
			(end -0.7874 -0.4064)
			(stroke
				(width 0.1524)
				(type default)
			)
			(layer "F.SilkS")
		)
		(fp_line
			(start -0.12065 -0.305054)
			(end -0.12065 -0.2794)
			(stroke
				(width 0.1)
				(type default)
			)
			(layer "F.Fab")
		)
		(fp_line
			(start -0.67945 -0.305054)
			(end -0.12065 -0.305054)
			(stroke
				(width 0.1)
				(type default)
			)
			(layer "F.Fab")
		)
		(fp_line
			(start 0.67945 -0.3048)
			(end 0.67945 0.3048)
			(stroke
				(width 0.1)
				(type default)
			)
			(layer "F.Fab")
		)
		(fp_line
			(start 0.12065 -0.3048)
			(end 0.67945 -0.3048)
			(stroke
				(width 0.1)
				(type default)
			)
			(layer "F.Fab")
		)
		(fp_line
			(start 0.12065 -0.2794)
			(end 0.12065 -0.3048)
			(stroke
				(width 0.1)
				(type default)
			)
			(layer "F.Fab")
		)
		(fp_line
			(start -0.12065 -0.2794)
			(end 0.12065 -0.2794)
			(stroke
				(width 0.1)
				(type default)
			)
			(layer "F.Fab")
		)
		(fp_line
			(start 0.120396 0.2794)
			(end -0.12065 0.2794)
			(stroke
				(width 0.1)
				(type default)
			)
			(layer "F.Fab")
		)
		(fp_line
			(start -0.12065 0.2794)
			(end -0.12065 0.3048)
			(stroke
				(width 0.1)
				(type default)
			)
			(layer "F.Fab")
		)
		(fp_line
			(start 0.67945 0.3048)
			(end 0.120396 0.3048)
			(stroke
				(width 0.1)
				(type default)
			)
			(layer "F.Fab")
		)
		(fp_line
			(start 0.120396 0.3048)
			(end 0.120396 0.2794)
			(stroke
				(width 0.1)
				(type default)
			)
			(layer "F.Fab")
		)
		(fp_line
			(start -0.12065 0.3048)
			(end -0.67945 0.3048)
			(stroke
				(width 0.1)
				(type default)
			)
			(layer "F.Fab")
		)
		(fp_line
			(start -0.67945 0.3048)
			(end -0.67945 -0.305054)
			(stroke
				(width 0.1)
				(type default)
			)
			(layer "F.Fab")
		)
		(pad "1" smd circle
			(at -0.40005 0 90)
			(size 0 0)
			(layers "F.Cu" "F.Mask" "F.Paste")
			(net "PVDDCR_CPU1_P1_VCCS")
		)
		(pad "2" smd circle
			(at 0.40005 0 90)
			(size 0 0)
			(layers "F.Cu" "F.Mask" "F.Paste")
			(net "GND")
		)
	)
	(footprint ""
		(layer "F.Cu")
		(at 104.843834 -135.290052 90)
		(property "Reference" "PR152"
			(at 0 0 90)
			(layer "F.SilkS")
			(hide yes)
			(effects
				(font
					(size 1.27 1.27)
				)
			)
		)
		(property "Value" ""
			(at 0 0 90)
			(layer "F.Fab")
			(effects
				(font
					(size 1.27 1.27)
				)
			)
		)
		(duplicate_pad_numbers_are_jumpers no)
		(fp_line
			(start 0.7874 -0.4064)
			(end 0.7874 0.4064)
			(stroke
				(width 0.1524)
				(type default)
			)
			(layer "F.SilkS")
		)
		(fp_line
			(start -0.7874 -0.4064)
			(end 0.7874 -0.4064)
			(stroke
				(width 0.1524)
				(type default)
			)
			(layer "F.SilkS")
		)
		(fp_line
			(start 0.7874 0.4064)
			(end -0.7874 0.4064)
			(stroke
				(width 0.1524)
				(type default)
			)
			(layer "F.SilkS")
		)
		(fp_line
			(start -0.7874 0.4064)
			(end -0.7874 -0.4064)
			(stroke
				(width 0.1524)
				(type default)
			)
			(layer "F.SilkS")
		)
		(fp_line
			(start -0.12065 -0.305054)
			(end -0.12065 -0.2794)
			(stroke
				(width 0.1)
				(type default)
			)
			(layer "F.Fab")
		)
		(fp_line
			(start -0.67945 -0.305054)
			(end -0.12065 -0.305054)
			(stroke
				(width 0.1)
				(type default)
			)
			(layer "F.Fab")
		)
		(fp_line
			(start 0.67945 -0.3048)
			(end 0.67945 0.3048)
			(stroke
				(width 0.1)
				(type default)
			)
			(layer "F.Fab")
		)
		(fp_line
			(start 0.12065 -0.3048)
			(end 0.67945 -0.3048)
			(stroke
				(width 0.1)
				(type default)
			)
			(layer "F.Fab")
		)
		(fp_line
			(start 0.12065 -0.2794)
			(end 0.12065 -0.3048)
			(stroke
				(width 0.1)
				(type default)
			)
			(layer "F.Fab")
		)
		(fp_line
			(start -0.12065 -0.2794)
			(end 0.12065 -0.2794)
			(stroke
				(width 0.1)
				(type default)
			)
			(layer "F.Fab")
		)
		(fp_line
			(start 0.120396 0.2794)
			(end -0.12065 0.2794)
			(stroke
				(width 0.1)
				(type default)
			)
			(layer "F.Fab")
		)
		(fp_line
			(start -0.12065 0.2794)
			(end -0.12065 0.3048)
			(stroke
				(width 0.1)
				(type default)
			)
			(layer "F.Fab")
		)
		(fp_line
			(start 0.67945 0.3048)
			(end 0.120396 0.3048)
			(stroke
				(width 0.1)
				(type default)
			)
			(layer "F.Fab")
		)
		(fp_line
			(start 0.120396 0.3048)
			(end 0.120396 0.2794)
			(stroke
				(width 0.1)
				(type default)
			)
			(layer "F.Fab")
		)
		(fp_line
			(start -0.12065 0.3048)
			(end -0.67945 0.3048)
			(stroke
				(width 0.1)
				(type default)
			)
			(layer "F.Fab")
		)
		(fp_line
			(start -0.67945 0.3048)
			(end -0.67945 -0.305054)
			(stroke
				(width 0.1)
				(type default)
			)
			(layer "F.Fab")
		)
		(pad "1" smd circle
			(at -0.40005 0 90)
			(size 0 0)
			(layers "F.Cu" "F.Mask" "F.Paste")
			(net "P3V3_AUX")
		)
		(pad "2" smd circle
			(at 0.40005 0 90)
			(size 0 0)
			(layers "F.Cu" "F.Mask" "F.Paste")
			(net "PVDDCR_SOC_P1_EN_GD")
		)
	)
	(footprint ""
		(layer "F.Cu")
		(at 113.283238 -39.40175 -90)
		(property "Reference" "R6285"
			(at 0 0 270)
			(layer "F.SilkS")
			(hide yes)
			(effects
				(font
					(size 1.27 1.27)
				)
			)
		)
		(property "Value" ""
			(at 0 0 270)
			(layer "F.Fab")
			(effects
				(font
					(size 1.27 1.27)
				)
			)
		)
		(duplicate_pad_numbers_are_jumpers no)
		(fp_line
			(start -0.7874 0.4064)
			(end -0.7874 -0.4064)
			(stroke
				(width 0.1524)
				(type default)
			)
			(layer "F.SilkS")
		)
		(fp_line
			(start 0.7874 0.4064)
			(end -0.7874 0.4064)
			(stroke
				(width 0.1524)
				(type default)
			)
			(layer "F.SilkS")
		)
		(fp_line
			(start -0.7874 -0.4064)
			(end 0.7874 -0.4064)
			(stroke
				(width 0.1524)
				(type default)
			)
			(layer "F.SilkS")
		)
		(fp_line
			(start 0.7874 -0.4064)
			(end 0.7874 0.4064)
			(stroke
				(width 0.1524)
				(type default)
			)
			(layer "F.SilkS")
		)
		(fp_line
			(start -0.67945 0.3048)
			(end -0.67945 -0.305054)
			(stroke
				(width 0.1)
				(type default)
			)
			(layer "F.Fab")
		)
		(fp_line
			(start -0.12065 0.3048)
			(end -0.67945 0.3048)
			(stroke
				(width 0.1)
				(type default)
			)
			(layer "F.Fab")
		)
		(fp_line
			(start 0.120396 0.3048)
			(end 0.120396 0.2794)
			(stroke
				(width 0.1)
				(type default)
			)
			(layer "F.Fab")
		)
		(fp_line
			(start 0.67945 0.3048)
			(end 0.120396 0.3048)
			(stroke
				(width 0.1)
				(type default)
			)
			(layer "F.Fab")
		)
		(fp_line
			(start -0.12065 0.2794)
			(end -0.12065 0.3048)
			(stroke
				(width 0.1)
				(type default)
			)
			(layer "F.Fab")
		)
		(fp_line
			(start 0.120396 0.2794)
			(end -0.12065 0.2794)
			(stroke
				(width 0.1)
				(type default)
			)
			(layer "F.Fab")
		)
		(fp_line
			(start -0.12065 -0.2794)
			(end 0.12065 -0.2794)
			(stroke
				(width 0.1)
				(type default)
			)
			(layer "F.Fab")
		)
		(fp_line
			(start 0.12065 -0.2794)
			(end 0.12065 -0.3048)
			(stroke
				(width 0.1)
				(type default)
			)
			(layer "F.Fab")
		)
		(fp_line
			(start 0.12065 -0.3048)
			(end 0.67945 -0.3048)
			(stroke
				(width 0.1)
				(type default)
			)
			(layer "F.Fab")
		)
		(fp_line
			(start 0.67945 -0.3048)
			(end 0.67945 0.3048)
			(stroke
				(width 0.1)
				(type default)
			)
			(layer "F.Fab")
		)
		(fp_line
			(start -0.67945 -0.305054)
			(end -0.12065 -0.305054)
			(stroke
				(width 0.1)
				(type default)
			)
			(layer "F.Fab")
		)
		(fp_line
			(start -0.12065 -0.305054)
			(end -0.12065 -0.2794)
			(stroke
				(width 0.1)
				(type default)
			)
			(layer "F.Fab")
		)
		(pad "1" smd circle
			(at -0.40005 0 270)
			(size 0 0)
			(layers "F.Cu" "F.Mask" "F.Paste")
			(net "USB_HUB2_TI_PWRCTL_POL")
		)
		(pad "2" smd circle
			(at 0.40005 0 270)
			(size 0 0)
			(layers "F.Cu" "F.Mask" "F.Paste")
			(net "USB_HUB2_TI_PWRCTL_POL_MRP_VBUS_DET")
		)
	)
	(footprint ""
		(layer "F.Cu")
		(at 208.894426 -114.249708 180)
		(property "Reference" "R4608"
			(at 0 0 180)
			(layer "F.SilkS")
			(hide yes)
			(effects
				(font
					(size 1.27 1.27)
				)
			)
		)
		(property "Value" ""
			(at 0 0 180)
			(layer "F.Fab")
			(effects
				(font
					(size 1.27 1.27)
				)
			)
		)
		(duplicate_pad_numbers_are_jumpers no)
		(fp_line
			(start 0.7874 0.4064)
			(end -0.7874 0.4064)
			(stroke
				(width 0.1524)
				(type default)
			)
			(layer "F.SilkS")
		)
		(fp_line
			(start 0.7874 -0.4064)
			(end 0.7874 0.4064)
			(stroke
				(width 0.1524)
				(type default)
			)
			(layer "F.SilkS")
		)
		(fp_line
			(start -0.7874 0.4064)
			(end -0.7874 -0.4064)
			(stroke
				(width 0.1524)
				(type default)
			)
			(layer "F.SilkS")
		)
		(fp_line
			(start -0.7874 -0.4064)
			(end 0.7874 -0.4064)
			(stroke
				(width 0.1524)
				(type default)
			)
			(layer "F.SilkS")
		)
		(fp_line
			(start 0.67945 0.3048)
			(end 0.120396 0.3048)
			(stroke
				(width 0.1)
				(type default)
			)
			(layer "F.Fab")
		)
		(fp_line
			(start 0.67945 -0.3048)
			(end 0.67945 0.3048)
			(stroke
				(width 0.1)
				(type default)
			)
			(layer "F.Fab")
		)
		(fp_line
			(start 0.12065 -0.2794)
			(end 0.12065 -0.3048)
			(stroke
				(width 0.1)
				(type default)
			)
			(layer "F.Fab")
		)
		(fp_line
			(start 0.12065 -0.3048)
			(end 0.67945 -0.3048)
			(stroke
				(width 0.1)
				(type default)
			)
			(layer "F.Fab")
		)
		(fp_line
			(start 0.120396 0.3048)
			(end 0.120396 0.2794)
			(stroke
				(width 0.1)
				(type default)
			)
			(layer "F.Fab")
		)
		(fp_line
			(start 0.120396 0.2794)
			(end -0.12065 0.2794)
			(stroke
				(width 0.1)
				(type default)
			)
			(layer "F.Fab")
		)
		(fp_line
			(start -0.12065 0.3048)
			(end -0.67945 0.3048)
			(stroke
				(width 0.1)
				(type default)
			)
			(layer "F.Fab")
		)
		(fp_line
			(start -0.12065 0.2794)
			(end -0.12065 0.3048)
			(stroke
				(width 0.1)
				(type default)
			)
			(layer "F.Fab")
		)
		(fp_line
			(start -0.12065 -0.2794)
			(end 0.12065 -0.2794)
			(stroke
				(width 0.1)
				(type default)
			)
			(layer "F.Fab")
		)
		(fp_line
			(start -0.12065 -0.305054)
			(end -0.12065 -0.2794)
			(stroke
				(width 0.1)
				(type default)
			)
			(layer "F.Fab")
		)
		(fp_line
			(start -0.67945 0.3048)
			(end -0.67945 -0.305054)
			(stroke
				(width 0.1)
				(type default)
			)
			(layer "F.Fab")
		)
		(fp_line
			(start -0.67945 -0.305054)
			(end -0.12065 -0.305054)
			(stroke
				(width 0.1)
				(type default)
			)
			(layer "F.Fab")
		)
		(pad "1" smd circle
			(at -0.40005 0 180)
			(size 0 0)
			(layers "F.Cu" "F.Mask" "F.Paste")
			(net "GPU_FPGA_RST_R_N")
		)
		(pad "2" smd circle
			(at 0.40005 0 180)
			(size 0 0)
			(layers "F.Cu" "F.Mask" "F.Paste")
			(net "GPU_FPGA_RST_N")
		)
	)
)
